# BASEBOARD_FAB2 (Tioga Pass) — schematic netlist excerpt (pin names and nets, part order shuffled) for the footprints in the layout excerpt that follows; sources: Cadence DE-HDL packaged netlist, KiCad conversion of Wiwynn_Tioga_Pass_MB.brd

L30W1  CHOKE_4PIN  67 OHM EMPTY  pkg SM_B  page 253
  \1\  = USB3_P01_RXP
  \2\  = USB3_P01_FB_RXP
  \3\  = USB3_P01_FB_RXN
  \4\  = USB3_P01_RXN

C6P20  CAP  10UF 16V 10% X6S  pkg 0805  page 203 : A = VR_FET_SW_P12V_STBY_PVCCIN_CPU0 ; B = GND
C1E15  CAP  10UF 16V 10% X6S  pkg 0805  page 195 : A = P12V_PSU ; B = GND

(kicad_pcb
	(version 20260206)
	(generator "pcbnew")
	(generator_version "10.0")
	(general
		(thickness 1.6)
		(legacy_teardrops no)
	)
	(paper "A4")
	(title_block
		(title "Wiwynn_Tioga_Pass_MB.brd")
		(comment 1 "Tioga Pass / footprints 4700-4702 of 4770")
	)
	(layers
		(0 "F.Cu" signal "TOP")
		(4 "In1.Cu" signal "L2GND")
		(6 "In2.Cu" signal "L3")
		(8 "In3.Cu" signal "L4GND")
		(10 "In4.Cu" signal "L5")
		(12 "In5.Cu" signal "L6GND")
		(14 "In6.Cu" signal "L7VCC")
		(16 "In7.Cu" signal "L8VCC")
		(18 "In8.Cu" signal "L9GND")
		(20 "In9.Cu" signal "L10")
		(22 "In10.Cu" signal "L11GND")
		(24 "In11.Cu" signal "L12")
		(26 "In12.Cu" signal "L13GND")
		(2 "B.Cu" signal "BOTTOM")
		(9 "F.Adhes" user "F.Adhesive")
		(11 "B.Adhes" user "B.Adhesive")
		(13 "F.Paste" user "Package Geometry/Pastemask Top")
		(15 "B.Paste" user "Package Geometry/Pastemask Bottom")
		(5 "F.SilkS" user "Ref Des/Silkscreen Top")
		(7 "B.SilkS" user "Ref Des/Silkscreen Bottom")
		(1 "F.Mask" user "Board Geometry/Soldermask Top")
		(3 "B.Mask" user "Board Geometry/Soldermask Bottom")
		(17 "Dwgs.User" user "User.Drawings")
		(19 "Cmts.User" user "User.Comments")
		(21 "Eco1.User" user "User.Eco1")
		(23 "Eco2.User" user "User.Eco2")
		(25 "Edge.Cuts" user "Board Geometry/Outline")
		(27 "Margin" user)
		(31 "F.CrtYd" user "Package Geometry/Place Bound Top")
		(29 "B.CrtYd" user "Package Geometry/Place Bound Bottom")
		(35 "F.Fab" user "Ref Des/Assembly Top")
		(33 "B.Fab" user "Ref Des/Assembly Bottom")
	)
	(footprint ""
		(layer "B.Cu")
		(at 197.848728 -72.855582 90)
		(property "Reference" "C6P20"
			(at 0 0 90)
			(layer "B.SilkS")
			(hide yes)
			(effects
				(font
					(size 1.27 1.27)
				)
				(justify mirror)
			)
		)
		(property "Value" ""
			(at 0 0 90)
			(layer "B.Fab")
			(effects
				(font
					(size 1.27 1.27)
				)
				(justify mirror)
			)
		)
		(duplicate_pad_numbers_are_jumpers no)
		(fp_rect
			(start -0.7239 -0.2159)
			(end 0.7239 1.9939)
			(stroke
				(width 0)
				(type default)
			)
			(fill no)
			(layer "B.CrtYd")
		)
		(fp_line
			(start 0.7239 -0.2159)
			(end 0.7239 1.9939)
			(stroke
				(width 0.1)
				(type default)
			)
			(layer "B.Fab")
		)
		(fp_line
			(start -0.7239 -0.2159)
			(end 0.7239 -0.2159)
			(stroke
				(width 0.1)
				(type default)
			)
			(layer "B.Fab")
		)
		(fp_line
			(start 0.7239 1.9939)
			(end -0.7239 1.9939)
			(stroke
				(width 0.1)
				(type default)
			)
			(layer "B.Fab")
		)
		(fp_line
			(start -0.7239 1.9939)
			(end -0.7239 -0.2159)
			(stroke
				(width 0.1)
				(type default)
			)
			(layer "B.Fab")
		)
		(pad "1" smd rect
			(at 0 0 270)
			(size 1.27 1.016)
			(layers "B.Cu" "B.Mask" "B.Paste")
			(net "VR_FET_SW_P12V_STBY_PVCCIN_CPU0")
		)
		(pad "2" smd rect
			(at 0 1.778 270)
			(size 1.27 1.016)
			(layers "B.Cu" "B.Mask" "B.Paste")
			(net "GND")
		)
		(zone
			(layer "B.Cu")
			(hatch none 0.5)
			(connect_pads
				(clearance 0)
			)
			(min_thickness 0.25)
			(keepout
				(tracks not_allowed)
				(vias allowed)
				(pads allowed)
				(copperpour not_allowed)
				(footprints allowed)
			)
			(placement
				(enabled no)
				(sheetname "")
			)
			(fill
				(thermal_gap 0.5)
				(thermal_bridge_width 0.5)
				(island_removal_mode 0)
			)
			(polygon
				(pts
					(xy 198.356728 -72.220582) (xy 199.118728 -72.220582) (xy 199.118728 -73.490582) (xy 198.356728 -73.490582)
				)
			)
		)
	)
	(footprint ""
		(layer "B.Cu")
		(at 13.716 -54.889908 90)
		(property "Reference" "C1E15"
			(at 0 0 90)
			(layer "B.SilkS")
			(hide yes)
			(effects
				(font
					(size 1.27 1.27)
				)
				(justify mirror)
			)
		)
		(property "Value" ""
			(at 0 0 90)
			(layer "B.Fab")
			(effects
				(font
					(size 1.27 1.27)
				)
				(justify mirror)
			)
		)
		(duplicate_pad_numbers_are_jumpers no)
		(fp_rect
			(start -0.7239 -0.2159)
			(end 0.7239 1.9939)
			(stroke
				(width 0)
				(type default)
			)
			(fill no)
			(layer "B.CrtYd")
		)
		(fp_line
			(start 0.7239 -0.2159)
			(end 0.7239 1.9939)
			(stroke
				(width 0.1)
				(type default)
			)
			(layer "B.Fab")
		)
		(fp_line
			(start -0.7239 -0.2159)
			(end 0.7239 -0.2159)
			(stroke
				(width 0.1)
				(type default)
			)
			(layer "B.Fab")
		)
		(fp_line
			(start 0.7239 1.9939)
			(end -0.7239 1.9939)
			(stroke
				(width 0.1)
				(type default)
			)
			(layer "B.Fab")
		)
		(fp_line
			(start -0.7239 1.9939)
			(end -0.7239 -0.2159)
			(stroke
				(width 0.1)
				(type default)
			)
			(layer "B.Fab")
		)
		(pad "1" smd rect
			(at 0 0 270)
			(size 1.27 1.016)
			(layers "B.Cu" "B.Mask" "B.Paste")
			(net "P12V_PSU")
		)
		(pad "2" smd rect
			(at 0 1.778 270)
			(size 1.27 1.016)
			(layers "B.Cu" "B.Mask" "B.Paste")
			(net "GND")
		)
		(zone
			(layer "B.Cu")
			(hatch none 0.5)
			(connect_pads
				(clearance 0)
			)
			(min_thickness 0.25)
			(keepout
				(tracks not_allowed)
				(vias allowed)
				(pads allowed)
				(copperpour not_allowed)
				(footprints allowed)
			)
			(placement
				(enabled no)
				(sheetname "")
			)
			(fill
				(thermal_gap 0.5)
				(thermal_bridge_width 0.5)
				(island_removal_mode 0)
			)
			(polygon
				(pts
					(xy 14.224 -54.254908) (xy 14.986 -54.254908) (xy 14.986 -55.524908) (xy 14.224 -55.524908)
				)
			)
		)
	)
	(footprint ""
		(layer "B.Cu")
		(at 485.58577 -58.103262 180)
		(property "Reference" "L30W1"
			(at -0.127 -1.07188 180)
			(unlocked yes)
			(layer "B.SilkS")
			(effects
				(font
					(size 0.4064 0.254)
					(thickness 0.1524)
				)
				(justify left mirror)
			)
		)
		(property "Value" ""
			(at 0 0 0)
			(layer "B.Fab")
			(effects
				(font
					(size 1.27 1.27)
				)
				(justify mirror)
			)
		)
		(duplicate_pad_numbers_are_jumpers no)
		(fp_rect
			(start 0.08382 1.09982)
			(end -2.11582 -0.29972)
			(stroke
				(width 0)
				(type default)
			)
			(fill no)
			(layer "B.CrtYd")
		)
		(fp_line
			(start 0.08382 1.09982)
			(end 0.08382 -0.29972)
			(stroke
				(width 0.1)
				(type default)
			)
			(layer "B.Fab")
		)
		(fp_line
			(start 0.08382 -0.29972)
			(end -2.11582 -0.29972)
			(stroke
				(width 0.1)
				(type default)
			)
			(layer "B.Fab")
		)
		(fp_line
			(start -2.11582 1.09982)
			(end 0.08382 1.09982)
			(stroke
				(width 0.1)
				(type default)
			)
			(layer "B.Fab")
		)
		(fp_line
			(start -2.11582 -0.29972)
			(end -2.11582 1.09982)
			(stroke
				(width 0.1)
				(type default)
			)
			(layer "B.Fab")
		)
		(pad "1" smd rect
			(at 0 0)
			(size 1.27 0.508)
			(layers "B.Cu" "B.Mask" "B.Paste")
			(net "USB3_P01_RXP")
		)
		(pad "2" smd rect
			(at -2.032 0)
			(size 1.27 0.508)
			(layers "B.Cu" "B.Mask" "B.Paste")
			(net "USB3_P01_FB_RXP")
		)
		(pad "3" smd rect
			(at -2.032 0.8001)
			(size 1.27 0.508)
			(layers "B.Cu" "B.Mask" "B.Paste")
			(net "USB3_P01_FB_RXN")
		)
		(pad "4" smd rect
			(at 0 0.8001)
			(size 1.27 0.508)
			(layers "B.Cu" "B.Mask" "B.Paste")
			(net "USB3_P01_RXN")
		)
		(zone
			(layer "B.Cu")
			(hatch none 0.5)
			(connect_pads
				(clearance 0)
			)
			(min_thickness 0.25)
			(keepout
				(tracks not_allowed)
				(vias allowed)
				(pads allowed)
				(copperpour not_allowed)
				(footprints allowed)
			)
			(placement
				(enabled no)
				(sheetname "")
			)
			(fill
				(thermal_gap 0.5)
				(thermal_bridge_width 0.5)
				(island_removal_mode 0)
			)
			(polygon
				(pts
					(xy 484.95077 -58.649362) (xy 484.95077 -58.357262) (xy 486.22077 -58.357262) (xy 486.22077 -58.649362)
				)
			)
		)
		(zone
			(layer "B.Cu")
			(hatch none 0.5)
			(connect_pads
				(clearance 0)
			)
			(min_thickness 0.25)
			(keepout
				(tracks not_allowed)
				(vias allowed)
				(pads allowed)
				(copperpour not_allowed)
				(footprints allowed)
			)
			(placement
				(enabled no)
				(sheetname "")
			)
			(fill
				(thermal_gap 0.5)
				(thermal_bridge_width 0.5)
				(island_removal_mode 0)
			)
			(polygon
				(pts
					(xy 486.22077 -59.157362) (xy 486.98277 -59.157362) (xy 486.98277 -57.849262) (xy 486.22077 -57.849262)
				)
			)
		)
		(zone
			(layer "B.Cu")
			(hatch none 0.5)
			(connect_pads
				(clearance 0)
			)
			(min_thickness 0.25)
			(keepout
				(tracks allowed)
				(vias not_allowed)
				(pads allowed)
				(copperpour not_allowed)
				(footprints allowed)
			)
			(placement
				(enabled no)
				(sheetname "")
			)
			(fill
				(thermal_gap 0.5)
				(thermal_bridge_width 0.5)
				(island_removal_mode 0)
			)
			(polygon
				(pts
					(xy 486.22077 -57.849262) (xy 486.22077 -59.157362) (xy 486.98277 -59.157362) (xy 486.98277 -57.849262)
				)
			)
		)
	)
)
